(kicad_pcb
	(version 20260206)
	(generator "pcbnew")
	(generator_version "10.0")
	(general
		(thickness 1.6)
		(legacy_teardrops no)
	)
	(paper "A4")
	(title_block
		(title "Bryce Canyon_R.DPB_16317-1_OCP.brd")
		(comment 1 "Bryce Canyon / footprints 731-737 of 2099")
	)
	(layers
		(0 "F.Cu" signal "TOP")
		(4 "In1.Cu" signal "L2GND")
		(6 "In2.Cu" signal "L3")
		(8 "In3.Cu" signal "L4VCC")
		(10 "In4.Cu" signal "L5VCC")
		(12 "In5.Cu" signal "L6")
		(14 "In6.Cu" signal "L7GND")
		(2 "B.Cu" signal "BOTTOM")
		(9 "F.Adhes" user "F.Adhesive")
		(11 "B.Adhes" user "B.Adhesive")
		(13 "F.Paste" user "Package Geometry/Pastemask Top")
		(15 "B.Paste" user "Package Geometry/Pastemask Bottom")
		(5 "F.SilkS" user "Ref Des/Silkscreen Top")
		(7 "B.SilkS" user "Ref Des/Silkscreen Bottom")
		(1 "F.Mask" user "Board Geometry/Soldermask Top")
		(3 "B.Mask" user "Board Geometry/Soldermask Bottom")
		(17 "Dwgs.User" user "User.Drawings")
		(19 "Cmts.User" user "User.Comments")
		(21 "Eco1.User" user "User.Eco1")
		(23 "Eco2.User" user "User.Eco2")
		(25 "Edge.Cuts" user "Board Geometry/Outline")
		(27 "Margin" user)
		(31 "F.CrtYd" user "Package Geometry/Place Bound Top")
		(29 "B.CrtYd" user "Package Geometry/Place Bound Bottom")
		(35 "F.Fab" user "Ref Des/Assembly Top")
		(33 "B.Fab" user "Ref Des/Assembly Bottom")
	)
	(footprint ""
		(layer "F.Cu")
		(at 467.499954 -13.999972)
		(property "Reference" ""
			(at 0 0 0)
			(layer "F.SilkS")
			(hide yes)
			(effects
				(font
					(size 1.27 1.27)
				)
			)
		)
		(property "Value" "*"
			(at -6.3373 -0.4572 0)
			(unlocked yes)
			(layer "F.Fab")
			(hide yes)
			(effects
				(font
					(size 1.016 1.016)
					(thickness 0.1524)
				)
			)
		)
		(duplicate_pad_numbers_are_jumpers no)
		(fp_poly
			(pts
				(arc
					(start 5.0673 0)
					(mid -5.0673 0)
					(end 5.0673 0)
				)
			)
			(stroke
				(width 0)
				(type default)
			)
			(fill no)
			(layer "B.CrtYd")
		)
		(fp_poly
			(pts
				(arc
					(start 5.0673 0)
					(mid -5.0673 0)
					(end 5.0673 0)
				)
			)
			(stroke
				(width 0)
				(type default)
			)
			(fill no)
			(layer "F.CrtYd")
		)
		(fp_poly
			(pts
				(arc
					(start 5.0673 0)
					(mid -5.0673 0)
					(end 5.0673 0)
				)
			)
			(stroke
				(width 0)
				(type default)
			)
			(fill no)
			(layer "B.Fab")
		)
		(fp_poly
			(pts
				(arc
					(start 5.0673 0)
					(mid -5.0673 0)
					(end 5.0673 0)
				)
			)
			(stroke
				(width 0)
				(type default)
			)
			(fill no)
			(layer "F.Fab")
		)
		(pad "1" thru_hole circle
			(at 0 0)
			(size 9.525 9.525)
			(drill 3.556)
			(layers "*.Cu" "*.Mask")
			(remove_unused_layers no)
			(net "Net_32")
			(clearance -2.4765)
			(thermal_gap 0.3048)
			(padstack
				(mode front_inner_back)
				(layer "Inner"
					(shape circle)
					(size 3.9624 3.9624)
					(clearance 0.3048)
				)
				(layer "B.Cu"
					(shape circle)
					(size 9.525 9.525)
					(clearance -2.4765)
				)
			)
		)
		(zone
			(layers "F.Cu" "B.Cu" "In1.Cu" "In2.Cu" "In3.Cu" "In4.Cu" "In5.Cu" "In6.Cu")
			(hatch none 0.5)
			(connect_pads
				(clearance 0)
			)
			(min_thickness 0.25)
			(keepout
				(tracks not_allowed)
				(vias allowed)
				(pads allowed)
				(copperpour not_allowed)
				(footprints allowed)
			)
			(placement
				(enabled no)
				(sheetname "")
			)
			(fill
				(thermal_gap 0.5)
				(thermal_bridge_width 0.5)
				(island_removal_mode 0)
			)
			(polygon
				(pts
					(arc
						(start 472.262454 -13.999972)
						(mid 462.737454 -13.999972)
						(end 472.262454 -13.999972)
					)
				)
			)
		)
	)
	(footprint ""
		(layer "F.Cu")
		(at 244.37848 -196.72554 90)
		(property "Reference" "R79"
			(at 0 0 90)
			(layer "F.SilkS")
			(hide yes)
			(effects
				(font
					(size 1.27 1.27)
				)
			)
		)
		(property "Value" "4K7R2F-GP"
			(at 0.064008 -3.993896 90)
			(unlocked yes)
			(layer "F.Fab")
			(hide yes)
			(effects
				(font
					(size 1.016 1.016)
					(thickness 0.1524)
				)
			)
		)
		(property "Device Type" "R402H16"
			(at 0.064008 -5.517896 90)
			(unlocked yes)
			(layer "F.Fab")
			(hide yes)
			(effects
				(font
					(size 1.016 1.016)
					(thickness 0.1524)
				)
			)
		)
		(duplicate_pad_numbers_are_jumpers no)
		(fp_line
			(start 0.508 -0.9398)
			(end -0.508 -0.9398)
			(stroke
				(width 0.1524)
				(type default)
			)
			(layer "F.SilkS")
		)
		(fp_line
			(start -0.508 -0.9398)
			(end -0.508 0.9398)
			(stroke
				(width 0.1524)
				(type default)
			)
			(layer "F.SilkS")
		)
		(fp_rect
			(start -0.508 0.9398)
			(end 0.508 -0.9398)
			(stroke
				(width 0)
				(type default)
			)
			(fill no)
			(layer "F.CrtYd")
		)
		(fp_rect
			(start -0.508 0.9398)
			(end 0.508 -0.9398)
			(stroke
				(width 0)
				(type default)
			)
			(fill no)
			(layer "F.Fab")
		)
		(pad "1" smd custom
			(at 0 -0.4445 90)
			(size 0.1397 0.1397)
			(layers "F.Cu" "F.Mask" "F.Paste")
			(net "IO_EXP2_A2")
			(options
				(clearance outline)
				(anchor circle)
			)
			(primitives
				(gr_poly
					(pts
						(arc
							(start -0.1778 -0.2794)
							(mid -0.249642 -0.249642)
							(end -0.2794 -0.1778)
						)
						(arc
							(start -0.2794 0.1778)
							(mid -0.249642 0.249642)
							(end -0.1778 0.2794)
						)
						(arc
							(start 0.1778 0.2794)
							(mid 0.249642 0.249642)
							(end 0.2794 0.1778)
						)
						(arc
							(start 0.2794 -0.1778)
							(mid 0.249642 -0.249642)
							(end 0.1778 -0.2794)
						)
					)
					(width 0)
					(fill yes)
				)
			)
		)
		(pad "2" smd custom
			(at 0 0.4445 90)
			(size 0.1397 0.1397)
			(layers "F.Cu" "F.Mask" "F.Paste")
			(net "GND")
			(options
				(clearance outline)
				(anchor circle)
			)
			(primitives
				(gr_poly
					(pts
						(arc
							(start -0.1778 -0.2794)
							(mid -0.249642 -0.249642)
							(end -0.2794 -0.1778)
						)
						(arc
							(start -0.2794 0.1778)
							(mid -0.249642 0.249642)
							(end -0.1778 0.2794)
						)
						(arc
							(start 0.1778 0.2794)
							(mid 0.249642 0.249642)
							(end 0.2794 0.1778)
						)
						(arc
							(start 0.2794 -0.1778)
							(mid 0.249642 -0.249642)
							(end 0.1778 -0.2794)
						)
					)
					(width 0)
					(fill yes)
				)
			)
		)
	)
	(footprint ""
		(layer "F.Cu")
		(at 457.581 -274.955 180)
		(property "Reference" "C164"
			(at 0 0 180)
			(layer "F.SilkS")
			(hide yes)
			(effects
				(font
					(size 1.27 1.27)
				)
			)
		)
		(property "Value" "SC4D7U25V5KX-1-GP"
			(at -0.0762 -6.1214 180)
			(unlocked yes)
			(layer "F.Fab")
			(hide yes)
			(effects
				(font
					(size 1.016 1.016)
					(thickness 0.1524)
				)
			)
		)
		(property "Device Type" "C805H58"
			(at -0.0762 -8.1534 180)
			(unlocked yes)
			(layer "F.Fab")
			(hide yes)
			(effects
				(font
					(size 1.016 1.016)
					(thickness 0.1524)
				)
			)
		)
		(duplicate_pad_numbers_are_jumpers no)
		(fp_line
			(start 0.635 0)
			(end -0.635 0)
			(stroke
				(width 0.508)
				(type default)
			)
			(layer "F.SilkS")
		)
		(fp_rect
			(start -0.9652 1.778)
			(end 0.9652 -1.778)
			(stroke
				(width 0)
				(type default)
			)
			(fill no)
			(layer "F.CrtYd")
		)
		(fp_poly
			(pts
				(xy -0.9652 -1.778) (xy 0.9652 -1.778) (xy 0.9652 1.778) (xy -0.9652 1.778)
			)
			(stroke
				(width 0)
				(type default)
			)
			(fill no)
			(layer "F.Fab")
		)
		(pad "1" smd rect
			(at 0 -0.9652 180)
			(size 1.397 1.143)
			(layers "F.Cu" "F.Mask" "F.Paste")
			(net "P12V_HDD10")
		)
		(pad "2" smd rect
			(at 0 0.9652 180)
			(size 1.397 1.143)
			(layers "F.Cu" "F.Mask" "F.Paste")
			(net "GND")
		)
	)
	(footprint ""
		(layer "F.Cu")
		(at 241.995452 -363.046772 90)
		(property "Reference" "R1049"
			(at 0 0 90)
			(layer "F.SilkS")
			(hide yes)
			(effects
				(font
					(size 1.27 1.27)
				)
			)
		)
		(property "Value" "49K9R2F-L-GP"
			(at 0.064008 -3.993896 90)
			(unlocked yes)
			(layer "F.Fab")
			(hide yes)
			(effects
				(font
					(size 1.016 1.016)
					(thickness 0.1524)
				)
			)
		)
		(property "Device Type" "R402H16"
			(at 0.064008 -5.517896 90)
			(unlocked yes)
			(layer "F.Fab")
			(hide yes)
			(effects
				(font
					(size 1.016 1.016)
					(thickness 0.1524)
				)
			)
		)
		(duplicate_pad_numbers_are_jumpers no)
		(fp_line
			(start 0.508 -0.9398)
			(end -0.508 -0.9398)
			(stroke
				(width 0.1524)
				(type default)
			)
			(layer "F.SilkS")
		)
		(fp_line
			(start -0.508 -0.9398)
			(end -0.508 0.9398)
			(stroke
				(width 0.1524)
				(type default)
			)
			(layer "F.SilkS")
		)
		(fp_rect
			(start -0.508 0.9398)
			(end 0.508 -0.9398)
			(stroke
				(width 0)
				(type default)
			)
			(fill no)
			(layer "F.CrtYd")
		)
		(fp_rect
			(start -0.508 0.9398)
			(end 0.508 -0.9398)
			(stroke
				(width 0)
				(type default)
			)
			(fill no)
			(layer "F.Fab")
		)
		(pad "1" smd custom
			(at 0 -0.4445 90)
			(size 0.1397 0.1397)
			(layers "F.Cu" "F.Mask" "F.Paste")
			(net "P12V_IN")
			(options
				(clearance outline)
				(anchor circle)
			)
			(primitives
				(gr_poly
					(pts
						(arc
							(start -0.1778 -0.2794)
							(mid -0.249642 -0.249642)
							(end -0.2794 -0.1778)
						)
						(arc
							(start -0.2794 0.1778)
							(mid -0.249642 0.249642)
							(end -0.1778 0.2794)
						)
						(arc
							(start 0.1778 0.2794)
							(mid 0.249642 0.249642)
							(end 0.2794 0.1778)
						)
						(arc
							(start 0.2794 -0.1778)
							(mid 0.249642 -0.249642)
							(end 0.1778 -0.2794)
						)
					)
					(width 0)
					(fill yes)
				)
			)
		)
		(pad "2" smd custom
			(at 0 0.4445 90)
			(size 0.1397 0.1397)
			(layers "F.Cu" "F.Mask" "F.Paste")
			(net "MB3_CM_UV_R")
			(options
				(clearance outline)
				(anchor circle)
			)
			(primitives
				(gr_poly
					(pts
						(arc
							(start -0.1778 -0.2794)
							(mid -0.249642 -0.249642)
							(end -0.2794 -0.1778)
						)
						(arc
							(start -0.2794 0.1778)
							(mid -0.249642 0.249642)
							(end -0.1778 0.2794)
						)
						(arc
							(start 0.1778 0.2794)
							(mid 0.249642 0.249642)
							(end 0.2794 0.1778)
						)
						(arc
							(start 0.2794 -0.1778)
							(mid 0.249642 -0.249642)
							(end 0.1778 -0.2794)
						)
					)
					(width 0)
					(fill yes)
				)
			)
		)
	)
	(footprint ""
		(layer "F.Cu")
		(at 111.975646 -29.7434)
		(property "Reference" "C389"
			(at 0 0 0)
			(layer "F.SilkS")
			(hide yes)
			(effects
				(font
					(size 1.27 1.27)
				)
			)
		)
		(property "Value" "SCD033U25V2KX-GP"
			(at 1.1811 -2.7051 0)
			(unlocked yes)
			(layer "F.Fab")
			(hide yes)
			(effects
				(font
					(size 1.016 1.016)
					(thickness 0.1524)
				)
			)
		)
		(property "Device Type" "C402H22"
			(at 1.1811 -4.2291 0)
			(unlocked yes)
			(layer "F.Fab")
			(hide yes)
			(effects
				(font
					(size 1.016 1.016)
					(thickness 0.1524)
				)
			)
		)
		(duplicate_pad_numbers_are_jumpers no)
		(fp_rect
			(start -0.4318 0.9525)
			(end 0.4318 -0.9525)
			(stroke
				(width 0)
				(type default)
			)
			(fill no)
			(layer "F.CrtYd")
		)
		(fp_rect
			(start -0.4318 0.9525)
			(end 0.4318 -0.9525)
			(stroke
				(width 0)
				(type default)
			)
			(fill no)
			(layer "F.Fab")
		)
		(pad "1" smd custom
			(at 0 -0.4445)
			(size 0.1524 0.1524)
			(layers "F.Cu" "F.Mask" "F.Paste")
			(net "SW_HDD_P27")
			(options
				(clearance outline)
				(anchor circle)
			)
			(primitives
				(gr_poly
					(pts
						(arc
							(start 0.3048 -0.2032)
							(mid 0.275042 -0.275042)
							(end 0.2032 -0.3048)
						)
						(arc
							(start -0.2032 -0.3048)
							(mid -0.275042 -0.275042)
							(end -0.3048 -0.2032)
						)
						(arc
							(start -0.3048 0.2032)
							(mid -0.275042 0.275042)
							(end -0.2032 0.3048)
						)
						(arc
							(start 0.2032 0.3048)
							(mid 0.275042 0.275042)
							(end 0.3048 0.2032)
						)
					)
					(width 0)
					(fill yes)
				)
			)
		)
		(pad "2" smd custom
			(at 0 0.4445)
			(size 0.1524 0.1524)
			(layers "F.Cu" "F.Mask" "F.Paste")
			(net "GND")
			(options
				(clearance outline)
				(anchor circle)
			)
			(primitives
				(gr_poly
					(pts
						(arc
							(start 0.3048 -0.2032)
							(mid 0.275042 -0.275042)
							(end 0.2032 -0.3048)
						)
						(arc
							(start -0.2032 -0.3048)
							(mid -0.275042 -0.275042)
							(end -0.3048 -0.2032)
						)
						(arc
							(start -0.3048 0.2032)
							(mid -0.275042 0.275042)
							(end -0.2032 0.3048)
						)
						(arc
							(start 0.2032 0.3048)
							(mid 0.275042 0.275042)
							(end 0.3048 0.2032)
						)
					)
					(width 0)
					(fill yes)
				)
			)
		)
	)
	(footprint ""
		(layer "F.Cu")
		(at 55.372 -263.271)
		(property "Reference" "R175"
			(at 0 0 0)
			(layer "F.SilkS")
			(hide yes)
			(effects
				(font
					(size 1.27 1.27)
				)
			)
		)
		(property "Value" "2R6F-GP"
			(at -0.0508 -4.8514 0)
			(unlocked yes)
			(layer "F.Fab")
			(hide yes)
			(effects
				(font
					(size 1.016 1.016)
					(thickness 0.1524)
				)
			)
		)
		(property "Device Type" "R1206H26"
			(at 0 -6.3754 0)
			(unlocked yes)
			(layer "F.Fab")
			(hide yes)
			(effects
				(font
					(size 1.016 1.016)
					(thickness 0.1524)
				)
			)
		)
		(duplicate_pad_numbers_are_jumpers no)
		(fp_line
			(start -1.016 -2.2352)
			(end 1.016 -2.2352)
			(stroke
				(width 0.1524)
				(type default)
			)
			(layer "F.SilkS")
		)
		(fp_line
			(start -1.016 2.2352)
			(end -1.016 -2.2352)
			(stroke
				(width 0.1524)
				(type default)
			)
			(layer "F.SilkS")
		)
		(fp_line
			(start 1.016 -2.2352)
			(end 1.016 2.2352)
			(stroke
				(width 0.1524)
				(type default)
			)
			(layer "F.SilkS")
		)
		(fp_line
			(start 1.016 2.2352)
			(end -1.016 2.2352)
			(stroke
				(width 0.1524)
				(type default)
			)
			(layer "F.SilkS")
		)
		(fp_rect
			(start -1.0922 2.3114)
			(end 1.0922 -2.3114)
			(stroke
				(width 0)
				(type default)
			)
			(fill no)
			(layer "F.CrtYd")
		)
		(fp_poly
			(pts
				(xy -1.0922 -2.3114) (xy 1.0922 -2.3114) (xy 1.0922 2.3114) (xy -1.0922 2.3114)
			)
			(stroke
				(width 0)
				(type default)
			)
			(fill no)
			(layer "F.Fab")
		)
		(pad "1" smd rect
			(at 0 -1.397)
			(size 1.651 1.27)
			(layers "F.Cu" "F.Mask" "F.Paste")
			(net "P5V_HDD1")
		)
		(pad "2" smd rect
			(at 0 1.397)
			(size 1.651 1.27)
			(layers "F.Cu" "F.Mask" "F.Paste")
			(net "5V_PRE_1")
		)
	)
	(footprint ""
		(layer "F.Cu")
		(at 115.316 -141.224 180)
		(property "Reference" "Q63"
			(at 0 0 180)
			(layer "F.SilkS")
			(hide yes)
			(effects
				(font
					(size 1.27 1.27)
				)
			)
		)
		(property "Value" "AO4406AL-GP"
			(at -3.707384 -1.5367 180)
			(unlocked yes)
			(layer "F.Fab")
			(hide yes)
			(effects
				(font
					(size 1.016 1.016)
					(thickness 0.1524)
				)
			)
		)
		(property "Device Type" "SOIC8H69"
			(at -3.707384 -3.0607 180)
			(unlocked yes)
			(layer "F.Fab")
			(hide yes)
			(effects
				(font
					(size 1.016 1.016)
					(thickness 0.1524)
				)
			)
		)
		(duplicate_pad_numbers_are_jumpers no)
		(fp_line
			(start 2.1336 1.4224)
			(end 2.1336 -1.4224)
			(stroke
				(width 0.1524)
				(type default)
			)
			(layer "F.SilkS")
		)
		(fp_line
			(start 2.1336 -1.4224)
			(end -2.7432 -1.4224)
			(stroke
				(width 0.1524)
				(type default)
			)
			(layer "F.SilkS")
		)
		(fp_line
			(start -2.1844 -0.0508)
			(end -2.7178 0.508)
			(stroke
				(width 0.1524)
				(type default)
			)
			(layer "F.SilkS")
		)
		(fp_line
			(start -2.6289 3.4417)
			(end -2.6289 1.4732)
			(stroke
				(width 0.381)
				(type default)
			)
			(layer "F.SilkS")
		)
		(fp_line
			(start -2.7178 -0.508)
			(end -2.1844 -0.0508)
			(stroke
				(width 0.1524)
				(type default)
			)
			(layer "F.SilkS")
		)
		(fp_line
			(start -2.7432 1.4224)
			(end 2.1336 1.4224)
			(stroke
				(width 0.1524)
				(type default)
			)
			(layer "F.SilkS")
		)
		(fp_line
			(start -2.7432 1.4224)
			(end -2.6416 1.4224)
			(stroke
				(width 0.1524)
				(type default)
			)
			(layer "F.SilkS")
		)
		(fp_line
			(start -2.7432 -1.4224)
			(end -2.7432 1.4224)
			(stroke
				(width 0.1524)
				(type default)
			)
			(layer "F.SilkS")
		)
		(fp_poly
			(pts
				(xy -2.2098 -1.4224) (xy -2.2098 1.4224) (xy 2.2098 1.4224) (xy 2.2098 -1.4224)
			)
			(stroke
				(width 0)
				(type default)
			)
			(fill yes)
			(layer "F.SilkS")
		)
		(fp_rect
			(start -2.450084 2.999994)
			(end 2.450084 -2.999994)
			(stroke
				(width 0)
				(type default)
			)
			(fill no)
			(layer "F.CrtYd")
		)
		(fp_poly
			(pts
				(xy -2.8194 3.6322) (xy -2.8194 -3.6322) (xy 2.8194 -3.6322) (xy 2.8194 1.18364) (xy 2.450084 1.18364)
				(xy 2.450084 -2.999994) (xy -2.450084 -2.999994) (xy -2.450084 2.999994) (xy 2.450084 2.999994)
				(xy 2.450084 1.18618) (xy 2.8194 1.18618) (xy 2.8194 3.6322)
			)
			(stroke
				(width 0)
				(type default)
			)
			(fill no)
			(layer "F.CrtYd")
		)
		(fp_rect
			(start -2.8194 3.6322)
			(end 2.8194 -3.6322)
			(stroke
				(width 0)
				(type default)
			)
			(fill no)
			(layer "F.Fab")
		)
		(pad "1" smd rect
			(at -1.905 2.54 180)
			(size 0.635 1.651)
			(layers "F.Cu" "F.Mask" "F.Paste")
			(net "P5V_HDD15")
		)
		(pad "2" smd rect
			(at -0.635 2.54 180)
			(size 0.635 1.651)
			(layers "F.Cu" "F.Mask" "F.Paste")
			(net "P5V_HDD15")
		)
		(pad "3" smd rect
			(at 0.635 2.54 180)
			(size 0.635 1.651)
			(layers "F.Cu" "F.Mask" "F.Paste")
			(net "P5V_HDD15")
		)
		(pad "4" smd rect
			(at 1.905 2.54 180)
			(size 0.635 1.651)
			(layers "F.Cu" "F.Mask" "F.Paste")
			(net "SW_HDD_P15")
		)
		(pad "5" smd rect
			(at 1.905 -2.54 180)
			(size 0.635 1.651)
			(layers "F.Cu" "F.Mask" "F.Paste")
			(net "P5V_B_2")
		)
		(pad "6" smd rect
			(at 0.635 -2.54 180)
			(size 0.635 1.651)
			(layers "F.Cu" "F.Mask" "F.Paste")
			(net "P5V_B_2")
		)
		(pad "7" smd rect
			(at -0.635 -2.54 180)
			(size 0.635 1.651)
			(layers "F.Cu" "F.Mask" "F.Paste")
			(net "P5V_B_2")
		)
		(pad "8" smd rect
			(at -1.905 -2.54 180)
			(size 0.635 1.651)
			(layers "F.Cu" "F.Mask" "F.Paste")
			(net "P5V_B_2")
		)
	)
)
